# T6G (Grand Teton) — schematic parts with pin connectivity, parts 4047–4196 of 8303; source: Cadence DE-HDL packaged netlist (pstxprt.dat, pstxnet.dat, pstchip.dat)

PR230  Q_RES  40.2K 1% CHIP  pkg 0402LF  page 217 : 1 = P5V_AUX ; 2 = PVDDCR_CPU1_P1_VMON
PR231  Q_RES  10K 1% CHIP  pkg 0402LF  page 217 : 1 = PVDDCR_CPU1_P1_VMON ; 2 = GND
PR232  Q_RES  1K 1% CHIP  pkg 0402LF  page 217 : 1 = P3V3_AUX ; 2 = PVDDIO_P1_EN_G
PR236  Q_RES  0 5% CHIP  pkg 0402LF  page 54 : 1 = SVID_PVDDCR_CPU1_P1_SVC_R ; 2 = SVID_PVDDCR_CPU1_P1_SVC
PR237  Q_RES  0 5% CHIP  pkg 0402LF  page 54 : 1 = SVID_PVDDCR_CPU1_P1_SVD_R ; 2 = SVID_PVDDCR_CPU1_P1_SVD
PR239  Q_RES  0 5% CHIP  pkg 0402LF  page 217 : 1 = SVID_PVDDCR_CPU1_P1_SVTI ; 2 = SVID_PVDDCR_CPU1_P1_SVTI_R
PR244  Q_RES  9.53K 1% CHIP  pkg 0402LF  page 217 : 1 = PVDDCR_CPU1_P1_EN1_ADDR_CFG ; 2 = GND
PR245  Q_RES  0 5% CHIP  pkg 0402LF  page 217 : 1 = VSENSE_PVDDCR_CPU1_P1_DP ; 2 = VSENSE_PVDDCR_CPU1_P1_VSEN0
PR246  Q_RES  0 5% CHIP  pkg 0402LF  page 217 : 1 = VSENSE_PVDDIO_P1_DP ; 2 = VSENSE_PVDDIO_P1_VSEN1
PR251  Q_RES  0 5% CHIP  pkg 0402LF  page 217 : 1 = P12V_AUX ; 2 = PVDDCR_CPU1_P1_VINSEN
PR253  Q_RES  1 1% CHIP  pkg 0402LF  page 217 : 1 = PVDDCR_CPU1_P1_VCC ; 2 = P3V3_AUX
PR254  Q_RES  8.87K 1% EMPTY  pkg 0402LF  page 218 : 1 = PVDDCR_CPU1_P1_LSET2 ; 2 = GND
PR255  Q_RES  8.87K 1% EMPTY  pkg 0402LF  page 218 : 1 = PVDDCR_CPU1_P1_LSET1 ; 2 = GND
PR256  Q_RES  2.2 1% CHIP  pkg 0402LF  page 218 : 1 = PVDDCR_CPU1_P1_PVCC ; 2 = PVDDCR_CPU1_P1_VCC1
PR257  Q_RES  2.2 1% CHIP  pkg 0402LF  page 218 : 1 = PVDDCR_CPU1_P1_PVCC ; 2 = PVDDCR_CPU1_P1_VCC2
PR258  Q_RES  5.6 1% CHIP  pkg 0402LF  page 218 : 1 = SW_PVDDCR_CPU1_P1_BOOT1 ; 2 = SW_PVDDCR_CPU1_P1_BOOT1_R
PR259  Q_RES  5.6 1% CHIP  pkg 0402LF  page 218 : 1 = SW_PVDDCR_CPU1_P1_BOOT2 ; 2 = SW_PVDDCR_CPU1_P1_BOOT2_R
PR260  Q_RES  0 5% CHIP  pkg 0402LF  page 218 : 1 = PVDDCR_CPU1_P1_VOS2 ; 2 = PVDDCR_CPU1_P1
PR261  Q_RES  0 5% CHIP  pkg 0402LF  page 218 : 1 = PVDDCR_CPU1_P1_VOS1 ; 2 = PVDDCR_CPU1_P1
PR262  Q_RES  8.87K 1% EMPTY  pkg 0402LF  page 219 : 1 = PVDDCR_CPU1_P1_LSET4 ; 2 = GND
PR263  Q_RES  8.87K 1% EMPTY  pkg 0402LF  page 219 : 1 = PVDDCR_CPU1_P1_LSET3 ; 2 = GND
PR264  Q_RES  2.2 1% CHIP  pkg 0402LF  page 219 : 1 = PVDDCR_CPU1_P1_PVCC ; 2 = PVDDCR_CPU1_P1_VCC4
PR265  Q_RES  2.2 1% CHIP  pkg 0402LF  page 219 : 1 = PVDDCR_CPU1_P1_PVCC ; 2 = PVDDCR_CPU1_P1_VCC3
PR266  Q_RES  5.6 1% CHIP  pkg 0402LF  page 219 : 1 = SW_PVDDCR_CPU1_P1_BOOT4 ; 2 = SW_PVDDCR_CPU1_P1_BOOT4_R
PR267  Q_RES  5.6 1% CHIP  pkg 0402LF  page 219 : 1 = SW_PVDDCR_CPU1_P1_BOOT3 ; 2 = SW_PVDDCR_CPU1_P1_BOOT3_R
PR268  Q_RES  0 5% CHIP  pkg 0402LF  page 219 : 1 = PVDDCR_CPU1_P1_VOS4 ; 2 = PVDDCR_CPU1_P1
PR269  Q_RES  0 5% CHIP  pkg 0402LF  page 219 : 1 = PVDDCR_CPU1_P1_VOS3 ; 2 = PVDDCR_CPU1_P1
PR270  Q_RES  8.87K 1% EMPTY  pkg 0402LF  page 220 : 1 = PVDDCR_CPU1_P1_LSET5 ; 2 = GND
PR271  Q_RES  2.2 1% CHIP  pkg 0402LF  page 220 : 1 = PVDDCR_CPU1_P1_PVCC ; 2 = PVDDCR_CPU1_P1_VCC5
PR272  Q_RES  5.6 1% CHIP  pkg 0402LF  page 220 : 1 = SW_PVDDCR_CPU1_P1_BOOT5 ; 2 = SW_PVDDCR_CPU1_P1_BOOT5_R
PR273  Q_RES  0 5% CHIP  pkg 0402LF  page 220 : 1 = PVDDCR_CPU1_P1_VOS5 ; 2 = PVDDCR_CPU1_P1
PR274  Q_RES  8.87K 1% EMPTY  pkg 0402LF  page 222 : 1 = PVDDIO_P1_LSET2 ; 2 = GND
PR275  Q_RES  8.87K 1% EMPTY  pkg 0402LF  page 222 : 1 = PVDDIO_P1_LSET1 ; 2 = GND
PR276  Q_RES  2.2 1% CHIP  pkg 0402LF  page 222 : 1 = PVDDCR_CPU1_P1_PVCC ; 2 = PVDDIO_P1_VCC2
PR277  Q_RES  2.2 1% CHIP  pkg 0402LF  page 222 : 1 = PVDDCR_CPU1_P1_PVCC ; 2 = PVDDIO_P1_VCC1
PR278  Q_RES  5.6 1% CHIP  pkg 0402LF  page 222 : 1 = SW_PVDDIO_P1_BOOT2 ; 2 = SW_PVDDIO_P1_BOOT2_R
PR279  Q_RES  5.6 1% CHIP  pkg 0402LF  page 222 : 1 = SW_PVDDIO_P1_BOOT1 ; 2 = SW_PVDDIO_P1_BOOT1_R
PR280  Q_RES  0 5% CHIP  pkg 0402LF  page 222 : 1 = PVDDIO_P1_VOS1 ; 2 = PVDDIO_P1
PR281  Q_RES  0 5% CHIP  pkg 0402LF  page 222 : 1 = PVDDIO_P1_VOS2 ; 2 = PVDDIO_P1
PR283  Q_RES  0 5% CHIP  pkg 0402LF  page 193 : 1 = SVID_PVDDCR_CPU0_P0_SVTI ; 2 = GND
PR284  Q_RES  1K 1% EMPTY  pkg 0402LF  page 193 : 1 = PVDD18_S5_P0 ; 2 = SVID_PVDDCR_CPU0_P0_SVTI
PR285  Q_RES  1K 1% CHIP  pkg 0402LF  page 193 : 1 = P3V3_AUX ; 2 = PVDDCR_SOC_P0_EN_GD
PR288  Q_RES  49.9 1% CHIP  pkg 0402LF  page 224 : 1 = VSENSE_VSS_SENSE_C_P1 ; 2 = GND
PR290  Q_RES  40.2K 1% CHIP  pkg 0402LF  page 193 : 1 = P5V_AUX ; 2 = PVDDCR_CPU0_P0_VMON
PR291  Q_RES  1.5 1% EMPTY  pkg 0402LF  page 206 : 1 = SW_PVDDIO_P0_SW4_RC ; 2 = GND
PR292  Q_RES  681 1% CHIP  pkg 0402LF  page 193 : 1 = PVDDCR_SOC_P0_EN//ADDR_CFG ; 2 = GND
PR294  Q_RES  49.9 1% CHIP  pkg 0402LF  page 193 : 1 = PVDDCR_CPU0_P0 ; 2 = VSENSE_PVDDCR_CPU0_P0_DP
PR295  Q_RES  49.9 1% CHIP  pkg 0402LF  page 193 : 1 = VSENSE_VSS_SENSE_A_P0 ; 2 = GND
PR296  Q_RES  49.9 1% CHIP  pkg 0402LF  page 193 : 1 = PVDDCR_SOC_P0 ; 2 = VSENSE_PVDDCR_SOC_P0_DP
PR297  Q_RES  49.9 1% CHIP  pkg 0402LF  page 193 : 1 = VSENSE_VSS_SENSE_A_P0 ; 2 = GND
PR302  Q_RES  0 5% CHIP  pkg 0402LF  page 27 : 1 = SVID_PVDDCR_CPU0_P0_SVC_R ; 2 = SVID_PVDDCR_CPU0_P0_SVC
PR303  Q_RES  0 5% CHIP  pkg 0402LF  page 27 : 1 = SVID_PVDDCR_CPU0_P0_SVD_R ; 2 = SVID_PVDDCR_CPU0_P0_SVD
PR305  Q_RES  0 5% CHIP  pkg 0402LF  page 193 : 1 = SVID_PVDDCR_CPU0_P0_SVTI ; 2 = SVID_PVDDCR_CPU0_P0_SVTI_R
PR306  Q_RES  0 5% CHIP  pkg 0402LF  page 193 : 1 = VSENSE_PVDDCR_CPU0_P0_DP ; 2 = VSENSE_PVDDCR_CPU0_P0_VSEN0
PR307  Q_RES  0 5% CHIP  pkg 0402LF  page 193 : 1 = VSENSE_PVDDCR_SOC_P0_DP ; 2 = VSENSE_PVDDCR_SOC_P0_VSEN1
PR314  Q_RES  0 5% CHIP  pkg 0402LF  page 193 : 1 = P12V_AUX ; 2 = PVDDCR_CPU0_P0_VINSEN
PR316  Q_RES  1 1% CHIP  pkg 0402LF  page 193 : 1 = PVDDCR_CPU0_P0_VCC ; 2 = P3V3_AUX
PR318  Q_RES  2.2 1% CHIP  pkg 0402LF  page 194 : 1 = PVDDCR_CPU0_P0_PVCC ; 2 = PVDDCR_CPU0_P0_VCC1
PR319  Q_RES  2.2 1% CHIP  pkg 0402LF  page 194 : 1 = PVDDCR_CPU0_P0_PVCC ; 2 = PVDDCR_CPU0_P0_VCC2
PR320  Q_RES  8.87K 1% EMPTY  pkg 0402LF  page 194 : 1 = GND ; 2 = PVDDCR_CPU0_P0_LSET1
PR321  Q_RES  8.87K 1% EMPTY  pkg 0402LF  page 194 : 1 = GND ; 2 = PVDDCR_CPU0_P0_LSET2
PR322  Q_RES  5.6 1% CHIP  pkg 0402LF  page 194 : 1 = SW_PVDDCR_CPU0_P0_BOOT1 ; 2 = SW_PVDDCR_CPU0_P0_BOOT1_RC
PR323  Q_RES  5.6 1% CHIP  pkg 0402LF  page 194 : 1 = SW_PVDDCR_CPU0_P0_BOOT2 ; 2 = SW_PVDDCR_CPU0_P0_BOOT2_RC
PR324  Q_RES  0 5% CHIP  pkg 0402LF  page 194 : 1 = PVDDCR_CPU0_P0_VOS1 ; 2 = PVDDCR_CPU0_P0
PR325  Q_RES  0 5% CHIP  pkg 0402LF  page 194 : 1 = PVDDCR_CPU0_P0_VOS2 ; 2 = PVDDCR_CPU0_P0
PR326  Q_RES  2.2 1% CHIP  pkg 0402LF  page 225 : 1 = PVDD11_S3_P1_PVCC ; 2 = PVDD11_S3_P1_VCC1
PR327  Q_RES  2.2 1% CHIP  pkg 0402LF  page 225 : 1 = PVDD11_S3_P1_PVCC ; 2 = PVDD11_S3_P1_VCC2
PR328  Q_RES  4.87K 1% EMPTY  pkg 0402LF  page 225 : 1 = GND ; 2 = PVDD11_S3_P1_LSET1
PR329  Q_RES  4.87K 1% EMPTY  pkg 0402LF  page 225 : 1 = GND ; 2 = PVDD11_S3_P1_LSET2
PR330  Q_RES  5.6 1% CHIP  pkg 0402LF  page 225 : 1 = SW_PVDD11_S3_P1_BOOT1 ; 2 = SW_PVDD11_S3_P1_BOOT1_RC
PR331  Q_RES  5.6 1% CHIP  pkg 0402LF  page 225 : 1 = SW_PVDD11_S3_P1_BOOT2 ; 2 = SW_PVDD11_S3_P1_BOOT2_RC
PR332  Q_RES  0 5% CHIP  pkg 0402LF  page 225 : 1 = PVDD11_S3_P1_VOS1 ; 2 = PVDD11_S3_P1
PR333  Q_RES  0 5% CHIP  pkg 0402LF  page 225 : 1 = PVDD11_S3_P1_VOS2 ; 2 = PVDD11_S3_P1
PR334  Q_RES  1K 1% CHIP  pkg 0402LF  page 198 : 1 = PVDDCR_SOC_P0 ; 2 = GND
PR335  Q_RES  0 5% CHIP  pkg 0402LF  page 211 : 1 = PVDDCR_CPU0_P1_PVCC ; 2 = P5V_AUX
PR336  Q_RES  0 5% EMPTY  pkg 0402LF  page 211 : 1 = PVDDCR_CPU0_P1_PVCC ; 2 = P3V3_AUX
PR337  Q_RES  1K 1% CHIP  pkg 0402LF  page 211 : 1 = PVDDCR_CPU0_P1 ; 2 = GND
PR339  Q_RES  1K 1% CHIP  pkg 0402LF  page 215 : 1 = PVDDCR_SOC_P1 ; 2 = GND
PR340  Q_RES  0 5% CHIP  pkg 0402LF  page 218 : 1 = PVDDCR_CPU1_P1_PVCC ; 2 = P5V_AUX
PR341  Q_RES  0 5% EMPTY  pkg 0402LF  page 218 : 1 = PVDDCR_CPU1_P1_PVCC ; 2 = P3V3_AUX
PR342  Q_RES  1K 1% CHIP  pkg 0402LF  page 218 : 1 = PVDDCR_CPU1_P1 ; 2 = GND
PR344  Q_RES  2.2 1% CHIP  pkg 0402LF  page 195 : 1 = PVDDCR_CPU0_P0_PVCC ; 2 = PVDDCR_CPU0_P0_VCC3
PR345  Q_RES  2.2 1% CHIP  pkg 0402LF  page 195 : 1 = PVDDCR_CPU0_P0_PVCC ; 2 = PVDDCR_CPU0_P0_VCC4
PR346  Q_RES  8.87K 1% EMPTY  pkg 0402LF  page 195 : 1 = GND ; 2 = PVDDCR_CPU0_P0_LSET3
PR347  Q_RES  8.87K 1% EMPTY  pkg 0402LF  page 195 : 1 = GND ; 2 = PVDDCR_CPU0_P0_LSET4
PR348  Q_RES  5.6 1% CHIP  pkg 0402LF  page 195 : 1 = SW_PVDDCR_CPU0_P0_BOOT3 ; 2 = SW_PVDDCR_CPU0_P0_BOOT3_RC
PR349  Q_RES  5.6 1% CHIP  pkg 0402LF  page 195 : 1 = SW_PVDDCR_CPU0_P0_BOOT4 ; 2 = SW_PVDDCR_CPU0_P0_BOOT4_RC
PR350  Q_RES  0 5% CHIP  pkg 0402LF  page 195 : 1 = PVDDCR_CPU0_P0_VOS3 ; 2 = PVDDCR_CPU0_P0
PR351  Q_RES  0 5% CHIP  pkg 0402LF  page 195 : 1 = PVDDCR_CPU0_P0_VOS4 ; 2 = PVDDCR_CPU0_P0
PR352  Q_RES  2.2 1% CHIP  pkg 0402LF  page 196 : 1 = PVDDCR_CPU0_P0_PVCC ; 2 = PVDDCR_CPU0_P0_VCC5
PR353  Q_RES  8.87K 1% EMPTY  pkg 0402LF  page 196 : 1 = GND ; 2 = PVDDCR_CPU0_P0_LSET5
PR354  Q_RES  5.6 1% CHIP  pkg 0402LF  page 196 : 1 = SW_PVDDCR_CPU0_P0_BOOT5 ; 2 = SW_PVDDCR_CPU0_P0_BOOT5_RC
PR355  Q_RES  0 5% CHIP  pkg 0402LF  page 196 : 1 = PVDDCR_CPU0_P0_VOS5 ; 2 = PVDDCR_CPU0_P0
PR356  Q_RES  2.2 1% CHIP  pkg 0402LF  page 198 : 1 = PVDDCR_CPU0_P0_PVCC ; 2 = PVDDCR_SOC_P0_VCC1
PR357  Q_RES  2.2 1% CHIP  pkg 0402LF  page 198 : 1 = PVDDCR_CPU0_P0_PVCC ; 2 = PVDDCR_SOC_P0_VCC2
PR358  Q_RES  8.87K 1% EMPTY  pkg 0402LF  page 198 : 1 = GND ; 2 = PVDDCR_SOC_P0_LSET1
PR359  Q_RES  8.87K 1% EMPTY  pkg 0402LF  page 198 : 1 = GND ; 2 = PVDDCR_SOC_P0_LSET2
PR360  Q_RES  5.6 1% CHIP  pkg 0402LF  page 198 : 1 = SW_PVDDCR_SOC_P0_BOOT1 ; 2 = SW_PVDDCR_SOC_P0_BOOT1_RC
PR361  Q_RES  5.6 1% CHIP  pkg 0402LF  page 198 : 1 = SW_PVDDCR_SOC_P0_BOOT2 ; 2 = SW_PVDDCR_SOC_P0_BOOT2_RC
PR362  Q_RES  0 5% CHIP  pkg 0402LF  page 198 : 1 = PVDDCR_SOC_P0_VOS1 ; 2 = PVDDCR_SOC_P0
PR363  Q_RES  0 5% CHIP  pkg 0402LF  page 198 : 1 = PVDDCR_SOC_P0_VOS2 ; 2 = PVDDCR_SOC_P0
PR364  Q_RES  2.2 1% CHIP  pkg 0402LF  page 199 : 1 = PVDDCR_CPU0_P0_PVCC ; 2 = PVDDCR_SOC_P0_VCC3
PR365  Q_RES  8.87K 1% EMPTY  pkg 0402LF  page 199 : 1 = GND ; 2 = PVDDCR_SOC_P0_LSET3
PR366  Q_RES  5.6 1% CHIP  pkg 0402LF  page 199 : 1 = SW_PVDDCR_SOC_P0_BOOT3 ; 2 = SW_PVDDCR_SOC_P0_BOOT3_RC
PR367  Q_RES  0 5% CHIP  pkg 0402LF  page 199 : 1 = PVDDCR_SOC_P0_VOS3 ; 2 = PVDDCR_SOC_P0
PR368  Q_RES  8.87K 1% EMPTY  pkg 0402LF  page 223 : 1 = PVDDIO_P1_LSET4 ; 2 = GND
PR369  Q_RES  8.87K 1% EMPTY  pkg 0402LF  page 223 : 1 = PVDDIO_P1_LSET3 ; 2 = GND
PR370  Q_RES  2.2 1% CHIP  pkg 0402LF  page 223 : 1 = PVDDCR_CPU1_P1_PVCC ; 2 = PVDDIO_P1_VCC4
PR371  Q_RES  2.2 1% CHIP  pkg 0402LF  page 223 : 1 = PVDDCR_CPU1_P1_PVCC ; 2 = PVDDIO_P1_VCC3
PR372  Q_RES  5.6 1% CHIP  pkg 0402LF  page 223 : 1 = SW_PVDDIO_P1_BOOT4 ; 2 = SW_PVDDIO_P1_BOOT4_R
PR373  Q_RES  5.6 1% CHIP  pkg 0402LF  page 223 : 1 = SW_PVDDIO_P1_BOOT3 ; 2 = SW_PVDDIO_P1_BOOT3_R
PR374  Q_RES  0 5% CHIP  pkg 0402LF  page 223 : 1 = PVDDIO_P1_VOS3 ; 2 = PVDDIO_P1
PR375  Q_RES  0 5% CHIP  pkg 0402LF  page 223 : 1 = PVDDIO_P1_VOS4 ; 2 = PVDDIO_P1
PR376  Q_RES  40.2K 1% CHIP  pkg 0402LF  page 224 : 1 = P5V_AUX ; 2 = PVDD11_S3_P1_VMON
PR378  Q_RES  1K 1% CHIP  pkg 0402LF  page 222 : 1 = PVDDIO_P1 ; 2 = GND
PR379  Q_RES  1.5 1% EMPTY  pkg 0402LF  page 206 : 1 = SW_PVDDIO_P0_SW3_RC ; 2 = GND
PR384  Q_RES  0 5% CHIP  pkg 0402LF  page 224 : 1 = VSENSE_PVDD11_S3_P1_DP ; 2 = VSENSE_PVDD11_S3_P1_R
PR387  Q_RES  0 5% CHIP  pkg 0402LF  page 225 : 1 = PVDD11_S3_P1_PVCC ; 2 = P5V_AUX
PR388  Q_RES  0 5% CHIP  pkg 0402LF  page 224 : 1 = P12V_AUX ; 2 = PVDD11_S3_P1_VINSEN
PR389  Q_RES  1.5 1% EMPTY  pkg 0402LF  page 208 : 1 = SW_PVDD11_S3_P0_SW2_RC ; 2 = GND
PR390  Q_RES  0 5% EMPTY  pkg 0402LF  page 224 : 1 = PVDD11_S3_P1_RESET_N_R ; 2 = GND
PR391  Q_RES  1K 1% EMPTY  pkg 0402LF  page 224 : 1 = PVDD11_S3_P1_RESET_N_R ; 2 = PVDD18_S5_P1
PR392  Q_RES  0 5% EMPTY  pkg 0402LF  page 224 : 1 = PVDD11_S3_P1_RESET_N_R ; 2 = PVDD11_S3_P1_RESET_N
PR393  Q_RES  1 1% CHIP  pkg 0402LF  page 224 : 1 = PVDD11_S3_P1_VCC ; 2 = P3V3_AUX
PR394  Q_RES  0 5% EMPTY  pkg 0402LF  page 225 : 1 = PVDD11_S3_P1_PVCC ; 2 = P3V3_AUX
PR395  Q_RES  1K 1% CHIP  pkg 0402LF  page 225 : 1 = PVDD11_S3_P1 ; 2 = GND
PR397  Q_RES  0 5% CHIP  pkg 0402LF  page 226 : 1 = P3V3_AUX ; 2 = PVDD18_S5_P1_VCC
PR398  Q_RES  0 5% CHIP  pkg 0402LF  page 226 : 1 = GND ; 2 = PVDD18_S5_P1_MODE
PR399  Q_RES  49.9 1% CHIP  pkg 0402LF  page 226 : 1 = GND ; 2 = PVDD18_SS_P1_RGND
PR400  Q_RES  10 1% CHIP  pkg 0402LF  page 226 : 1 = PVDD18_S5_P1_FB_RC ; 2 = VSENSE_PVDD18_S5_P1_DP
PR401  Q_RES  0 5% CHIP  pkg 0402LF  page 226 : 1 = PVDD18_SS_P1_RGND ; 2 = VSENSE_PVDD18_S5_P1_DN
PR402  Q_RES  49.9 1% CHIP  pkg 0402LF  page 226 : 1 = PVDD18_S5_P1 ; 2 = PVDD18_S5_P1_FB_RC
PR403  Q_RES  1K 1% CHIP  pkg 0402LF  page 226 : 1 = PVDD18_S5_P1 ; 2 = GND
PR406  Q_RES  0 5% CHIP  pkg 0402LF  page 224 : 1 = NC_PVDD11_S3_P1_IMON3 ; 2 = GND
PR407  Q_RES  0 5% CHIP  pkg 0402LF  page 224 : 1 = NC_PVDD11_S3_P1_IMON4 ; 2 = GND
PR408  Q_RES  0 5% CHIP  pkg 0402LF  page 224 : 1 = NC_PVDD11_S3_P1_IMON7 ; 2 = GND
PR409  Q_RES  0 5% CHIP  pkg 0402LF  page 224 : 1 = NC_PVDD11_S3_P1_IMON8 ; 2 = GND
PR410  Q_RES  1K 1% CHIP  pkg 0402LF  page 205 : 1 = PVDDIO_P0 ; 2 = GND
PR411  Q_RES  0 5% CHIP  pkg 0402LF  page 208 : 1 = PVDD11_S3_P0_PVCC ; 2 = P5V_AUX
PR412  Q_RES  0 5% CHIP  pkg 0402LF  page 207 : 1 = PVDD11_S3_P0_TEMP1 ; 2 = GND
PR413  Q_RES  0 5% EMPTY  pkg 0402LF  page 208 : 1 = PVDD11_S3_P0_PVCC ; 2 = P3V3_AUX
PR414  Q_RES  1K 1% CHIP  pkg 0402LF  page 208 : 1 = PVDD11_S3_P0 ; 2 = GND
PR415  Q_RES  0 5% CHIP  pkg 0402LF  page 224 : 1 = PVDD11_S3_P1_TEMP1 ; 2 = GND
PR416  Q_RES  2.2 1% CHIP  pkg 0402LF  page 203 : 1 = PVDDCR_CPU1_P0_PVCC ; 2 = PVDDCR_CPU1_P0_VCC6
PR417  Q_RES  0 5% CHIP  pkg 0402LF  page 209 : 1 = GND ; 2 = PVDD18_S5_P0_MODE
PR418  Q_RES  49.9 1% CHIP  pkg 0402LF  page 209 : 1 = GND ; 2 = PVDD18_S5_P0_RGND
PR419  Q_RES  0 5% CHIP  pkg 0402LF  page 207 : 1 = NC_PVDD11_S3_P0_IMON7 ; 2 = GND
PR420  Q_RES  5.6 1% CHIP  pkg 0402LF  page 203 : 1 = SW_PVDDCR_CPU1_P0_BOOT6 ; 2 = SW_PVDDCR_CPU1_P0_BOOT6_R
PR421  Q_RES  0 5% CHIP  pkg 0402LF  page 203 : 1 = PVDDCR_CPU1_P0_VOS6 ; 2 = PVDDCR_CPU1_P0
PR422  Q_RES  2.2 1% CHIP  pkg 0402LF  page 213 : 1 = PVDDCR_CPU0_P1_PVCC ; 2 = PVDDCR_CPU0_P1_VCC6
